(kicad_pcb
	(version 20260206)
	(generator "pcbnew")
	(generator_version "10.0")
	(general
		(thickness 1.6)
		(legacy_teardrops no)
	)
	(paper "A4")
	(title_block
		(title "Wiwynn_Tioga_Pass_MB.brd")
		(comment 1 "Tioga Pass / footprints 2669-2676 of 4770")
	)
	(layers
		(0 "F.Cu" signal "TOP")
		(4 "In1.Cu" signal "L2GND")
		(6 "In2.Cu" signal "L3")
		(8 "In3.Cu" signal "L4GND")
		(10 "In4.Cu" signal "L5")
		(12 "In5.Cu" signal "L6GND")
		(14 "In6.Cu" signal "L7VCC")
		(16 "In7.Cu" signal "L8VCC")
		(18 "In8.Cu" signal "L9GND")
		(20 "In9.Cu" signal "L10")
		(22 "In10.Cu" signal "L11GND")
		(24 "In11.Cu" signal "L12")
		(26 "In12.Cu" signal "L13GND")
		(2 "B.Cu" signal "BOTTOM")
		(9 "F.Adhes" user "F.Adhesive")
		(11 "B.Adhes" user "B.Adhesive")
		(13 "F.Paste" user "Package Geometry/Pastemask Top")
		(15 "B.Paste" user "Package Geometry/Pastemask Bottom")
		(5 "F.SilkS" user "Ref Des/Silkscreen Top")
		(7 "B.SilkS" user "Ref Des/Silkscreen Bottom")
		(1 "F.Mask" user "Board Geometry/Soldermask Top")
		(3 "B.Mask" user "Board Geometry/Soldermask Bottom")
		(17 "Dwgs.User" user "User.Drawings")
		(19 "Cmts.User" user "User.Comments")
		(21 "Eco1.User" user "User.Eco1")
		(23 "Eco2.User" user "User.Eco2")
		(25 "Edge.Cuts" user "Board Geometry/Outline")
		(27 "Margin" user)
		(31 "F.CrtYd" user "Package Geometry/Place Bound Top")
		(29 "B.CrtYd" user "Package Geometry/Place Bound Bottom")
		(35 "F.Fab" user "Ref Des/Assembly Top")
		(33 "B.Fab" user "Ref Des/Assembly Bottom")
	)
	(footprint ""
		(layer "B.Cu")
		(at 406.4762 -13.8303 180)
		(property "Reference" "C2T3"
			(at 0 0 0)
			(layer "B.SilkS")
			(hide yes)
			(effects
				(font
					(size 1.27 1.27)
				)
				(justify mirror)
			)
		)
		(property "Value" ""
			(at 0 0 0)
			(layer "B.Fab")
			(effects
				(font
					(size 1.27 1.27)
				)
				(justify mirror)
			)
		)
		(duplicate_pad_numbers_are_jumpers no)
		(fp_poly
			(pts
				(xy -0.3048 -0.1016) (xy -0.3048 0.9906) (xy 0.3048 0.9906) (xy 0.3048 -0.1016)
			)
			(stroke
				(width 0)
				(type default)
			)
			(fill no)
			(layer "B.CrtYd")
		)
		(fp_line
			(start 0.3048 0.9906)
			(end -0.3048 0.9906)
			(stroke
				(width 0.1)
				(type default)
			)
			(layer "B.Fab")
		)
		(fp_line
			(start 0.3048 -0.1016)
			(end 0.3048 0.9906)
			(stroke
				(width 0.1)
				(type default)
			)
			(layer "B.Fab")
		)
		(fp_line
			(start -0.3048 0.9906)
			(end -0.3048 -0.1016)
			(stroke
				(width 0.1)
				(type default)
			)
			(layer "B.Fab")
		)
		(fp_line
			(start -0.3048 -0.1016)
			(end 0.3048 -0.1016)
			(stroke
				(width 0.1)
				(type default)
			)
			(layer "B.Fab")
		)
		(pad "1" smd rect
			(at 0 0)
			(size 0.508 0.508)
			(layers "B.Cu" "B.Mask" "B.Paste")
			(net "P3V3_STBY")
		)
		(pad "2" smd rect
			(at 0 0.889)
			(size 0.508 0.508)
			(layers "B.Cu" "B.Mask" "B.Paste")
			(net "GND")
		)
		(zone
			(layer "B.Cu")
			(hatch none 0.5)
			(connect_pads
				(clearance 0)
			)
			(min_thickness 0.25)
			(keepout
				(tracks not_allowed)
				(vias allowed)
				(pads allowed)
				(copperpour not_allowed)
				(footprints allowed)
			)
			(placement
				(enabled no)
				(sheetname "")
			)
			(fill
				(thermal_gap 0.5)
				(thermal_bridge_width 0.5)
				(island_removal_mode 0)
			)
			(polygon
				(pts
					(xy 406.2222 -14.4653) (xy 406.7302 -14.4653) (xy 406.7302 -14.0843) (xy 406.2222 -14.0843)
				)
			)
		)
		(zone
			(layer "B.Cu")
			(hatch none 0.5)
			(connect_pads
				(clearance 0)
			)
			(min_thickness 0.25)
			(keepout
				(tracks allowed)
				(vias not_allowed)
				(pads allowed)
				(copperpour not_allowed)
				(footprints allowed)
			)
			(placement
				(enabled no)
				(sheetname "")
			)
			(fill
				(thermal_gap 0.5)
				(thermal_bridge_width 0.5)
				(island_removal_mode 0)
			)
			(polygon
				(pts
					(xy 406.2222 -14.0843) (xy 406.7302 -14.0843) (xy 406.7302 -14.4653) (xy 406.2222 -14.4653)
				)
			)
		)
	)
	(footprint ""
		(layer "B.Cu")
		(at 344.522806 -61.257434)
		(property "Reference" "C2U11"
			(at 0 0 0)
			(layer "B.SilkS")
			(hide yes)
			(effects
				(font
					(size 1.27 1.27)
				)
				(justify mirror)
			)
		)
		(property "Value" ""
			(at 0 0 0)
			(layer "B.Fab")
			(effects
				(font
					(size 1.27 1.27)
				)
				(justify mirror)
			)
		)
		(duplicate_pad_numbers_are_jumpers no)
		(fp_poly
			(pts
				(xy -0.3048 -0.1016) (xy -0.3048 0.9906) (xy 0.3048 0.9906) (xy 0.3048 -0.1016)
			)
			(stroke
				(width 0)
				(type default)
			)
			(fill no)
			(layer "B.CrtYd")
		)
		(fp_line
			(start -0.3048 -0.1016)
			(end 0.3048 -0.1016)
			(stroke
				(width 0.1)
				(type default)
			)
			(layer "B.Fab")
		)
		(fp_line
			(start -0.3048 0.9906)
			(end -0.3048 -0.1016)
			(stroke
				(width 0.1)
				(type default)
			)
			(layer "B.Fab")
		)
		(fp_line
			(start 0.3048 -0.1016)
			(end 0.3048 0.9906)
			(stroke
				(width 0.1)
				(type default)
			)
			(layer "B.Fab")
		)
		(fp_line
			(start 0.3048 0.9906)
			(end -0.3048 0.9906)
			(stroke
				(width 0.1)
				(type default)
			)
			(layer "B.Fab")
		)
		(pad "1" smd rect
			(at 0 0 180)
			(size 0.508 0.508)
			(layers "B.Cu" "B.Mask" "B.Paste")
			(net "P3E_CPU0_PE1_PCH_RXP<4>")
		)
		(pad "2" smd rect
			(at 0 0.889 180)
			(size 0.508 0.508)
			(layers "B.Cu" "B.Mask" "B.Paste")
			(net "P3E_CPU0_PE1_SS_RXP<4>")
		)
		(zone
			(layer "B.Cu")
			(hatch none 0.5)
			(connect_pads
				(clearance 0)
			)
			(min_thickness 0.25)
			(keepout
				(tracks allowed)
				(vias not_allowed)
				(pads allowed)
				(copperpour not_allowed)
				(footprints allowed)
			)
			(placement
				(enabled no)
				(sheetname "")
			)
			(fill
				(thermal_gap 0.5)
				(thermal_bridge_width 0.5)
				(island_removal_mode 0)
			)
			(polygon
				(pts
					(xy 344.776806 -61.003434) (xy 344.268806 -61.003434) (xy 344.268806 -60.622434) (xy 344.776806 -60.622434)
				)
			)
		)
	)
	(footprint ""
		(layer "B.Cu")
		(at 370.967 -135.636 180)
		(property "Reference" "C3M22"
			(at 0 0 0)
			(layer "B.SilkS")
			(hide yes)
			(effects
				(font
					(size 1.27 1.27)
				)
				(justify mirror)
			)
		)
		(property "Value" ""
			(at 0 0 0)
			(layer "B.Fab")
			(effects
				(font
					(size 1.27 1.27)
				)
				(justify mirror)
			)
		)
		(duplicate_pad_numbers_are_jumpers no)
		(fp_poly
			(pts
				(xy -0.3048 -0.1016) (xy -0.3048 0.9906) (xy 0.3048 0.9906) (xy 0.3048 -0.1016)
			)
			(stroke
				(width 0)
				(type default)
			)
			(fill no)
			(layer "B.CrtYd")
		)
		(fp_line
			(start 0.3048 0.9906)
			(end -0.3048 0.9906)
			(stroke
				(width 0.1)
				(type default)
			)
			(layer "B.Fab")
		)
		(fp_line
			(start 0.3048 -0.1016)
			(end 0.3048 0.9906)
			(stroke
				(width 0.1)
				(type default)
			)
			(layer "B.Fab")
		)
		(fp_line
			(start -0.3048 0.9906)
			(end -0.3048 -0.1016)
			(stroke
				(width 0.1)
				(type default)
			)
			(layer "B.Fab")
		)
		(fp_line
			(start -0.3048 -0.1016)
			(end 0.3048 -0.1016)
			(stroke
				(width 0.1)
				(type default)
			)
			(layer "B.Fab")
		)
		(pad "1" smd rect
			(at 0 0)
			(size 0.508 0.508)
			(layers "B.Cu" "B.Mask" "B.Paste")
			(net "P1V05_PCH_STBY")
		)
		(pad "2" smd rect
			(at 0 0.889)
			(size 0.508 0.508)
			(layers "B.Cu" "B.Mask" "B.Paste")
			(net "GND")
		)
		(zone
			(layer "B.Cu")
			(hatch none 0.5)
			(connect_pads
				(clearance 0)
			)
			(min_thickness 0.25)
			(keepout
				(tracks not_allowed)
				(vias allowed)
				(pads allowed)
				(copperpour not_allowed)
				(footprints allowed)
			)
			(placement
				(enabled no)
				(sheetname "")
			)
			(fill
				(thermal_gap 0.5)
				(thermal_bridge_width 0.5)
				(island_removal_mode 0)
			)
			(polygon
				(pts
					(xy 370.713 -136.271) (xy 371.221 -136.271) (xy 371.221 -135.89) (xy 370.713 -135.89)
				)
			)
		)
		(zone
			(layer "B.Cu")
			(hatch none 0.5)
			(connect_pads
				(clearance 0)
			)
			(min_thickness 0.25)
			(keepout
				(tracks allowed)
				(vias not_allowed)
				(pads allowed)
				(copperpour not_allowed)
				(footprints allowed)
			)
			(placement
				(enabled no)
				(sheetname "")
			)
			(fill
				(thermal_gap 0.5)
				(thermal_bridge_width 0.5)
				(island_removal_mode 0)
			)
			(polygon
				(pts
					(xy 370.713 -135.89) (xy 371.221 -135.89) (xy 371.221 -136.271) (xy 370.713 -136.271)
				)
			)
		)
	)
	(footprint ""
		(layer "B.Cu")
		(at 344.435176 -77.694536)
		(property "Reference" "C3P19"
			(at 0 0 0)
			(layer "B.SilkS")
			(hide yes)
			(effects
				(font
					(size 1.27 1.27)
				)
				(justify mirror)
			)
		)
		(property "Value" ""
			(at 0 0 0)
			(layer "B.Fab")
			(effects
				(font
					(size 1.27 1.27)
				)
				(justify mirror)
			)
		)
		(duplicate_pad_numbers_are_jumpers no)
		(fp_poly
			(pts
				(xy -0.3048 -0.1016) (xy -0.3048 0.9906) (xy 0.3048 0.9906) (xy 0.3048 -0.1016)
			)
			(stroke
				(width 0)
				(type default)
			)
			(fill no)
			(layer "B.CrtYd")
		)
		(fp_line
			(start -0.3048 -0.1016)
			(end 0.3048 -0.1016)
			(stroke
				(width 0.1)
				(type default)
			)
			(layer "B.Fab")
		)
		(fp_line
			(start -0.3048 0.9906)
			(end -0.3048 -0.1016)
			(stroke
				(width 0.1)
				(type default)
			)
			(layer "B.Fab")
		)
		(fp_line
			(start 0.3048 -0.1016)
			(end 0.3048 0.9906)
			(stroke
				(width 0.1)
				(type default)
			)
			(layer "B.Fab")
		)
		(fp_line
			(start 0.3048 0.9906)
			(end -0.3048 0.9906)
			(stroke
				(width 0.1)
				(type default)
			)
			(layer "B.Fab")
		)
		(pad "1" smd rect
			(at 0 0 180)
			(size 0.508 0.508)
			(layers "B.Cu" "B.Mask" "B.Paste")
			(net "P3E_CPU0_PE1_SS_TXP<2>")
		)
		(pad "2" smd rect
			(at 0 0.889 180)
			(size 0.508 0.508)
			(layers "B.Cu" "B.Mask" "B.Paste")
			(net "P3E_CPU0_PE1_SS_C_TXP<2>")
		)
		(zone
			(layer "B.Cu")
			(hatch none 0.5)
			(connect_pads
				(clearance 0)
			)
			(min_thickness 0.25)
			(keepout
				(tracks allowed)
				(vias not_allowed)
				(pads allowed)
				(copperpour not_allowed)
				(footprints allowed)
			)
			(placement
				(enabled no)
				(sheetname "")
			)
			(fill
				(thermal_gap 0.5)
				(thermal_bridge_width 0.5)
				(island_removal_mode 0)
			)
			(polygon
				(pts
					(xy 344.689176 -77.440536) (xy 344.181176 -77.440536) (xy 344.181176 -77.059536) (xy 344.689176 -77.059536)
				)
			)
		)
	)
	(footprint ""
		(layer "B.Cu")
		(at 30.452568 -17.723612 90)
		(property "Reference" "C9T7"
			(at 0 0 90)
			(layer "B.SilkS")
			(hide yes)
			(effects
				(font
					(size 1.27 1.27)
				)
				(justify mirror)
			)
		)
		(property "Value" ""
			(at 0 0 90)
			(layer "B.Fab")
			(effects
				(font
					(size 1.27 1.27)
				)
				(justify mirror)
			)
		)
		(duplicate_pad_numbers_are_jumpers no)
		(fp_poly
			(pts
				(xy -0.3048 -0.1016) (xy -0.3048 0.9906) (xy 0.3048 0.9906) (xy 0.3048 -0.1016)
			)
			(stroke
				(width 0)
				(type default)
			)
			(fill no)
			(layer "B.CrtYd")
		)
		(fp_line
			(start 0.3048 -0.1016)
			(end 0.3048 0.9906)
			(stroke
				(width 0.1)
				(type default)
			)
			(layer "B.Fab")
		)
		(fp_line
			(start -0.3048 -0.1016)
			(end 0.3048 -0.1016)
			(stroke
				(width 0.1)
				(type default)
			)
			(layer "B.Fab")
		)
		(fp_line
			(start 0.3048 0.9906)
			(end -0.3048 0.9906)
			(stroke
				(width 0.1)
				(type default)
			)
			(layer "B.Fab")
		)
		(fp_line
			(start -0.3048 0.9906)
			(end -0.3048 -0.1016)
			(stroke
				(width 0.1)
				(type default)
			)
			(layer "B.Fab")
		)
		(pad "1" smd rect
			(at 0 0 270)
			(size 0.508 0.508)
			(layers "B.Cu" "B.Mask" "B.Paste")
			(net "M_G_VREF")
		)
		(pad "2" smd rect
			(at 0 0.889 270)
			(size 0.508 0.508)
			(layers "B.Cu" "B.Mask" "B.Paste")
			(net "GND")
		)
		(zone
			(layer "B.Cu")
			(hatch none 0.5)
			(connect_pads
				(clearance 0)
			)
			(min_thickness 0.25)
			(keepout
				(tracks allowed)
				(vias not_allowed)
				(pads allowed)
				(copperpour not_allowed)
				(footprints allowed)
			)
			(placement
				(enabled no)
				(sheetname "")
			)
			(fill
				(thermal_gap 0.5)
				(thermal_bridge_width 0.5)
				(island_removal_mode 0)
			)
			(polygon
				(pts
					(xy 30.706568 -17.977612) (xy 30.706568 -17.469612) (xy 31.087568 -17.469612) (xy 31.087568 -17.977612)
				)
			)
		)
		(zone
			(layer "B.Cu")
			(hatch none 0.5)
			(connect_pads
				(clearance 0)
			)
			(min_thickness 0.25)
			(keepout
				(tracks not_allowed)
				(vias allowed)
				(pads allowed)
				(copperpour not_allowed)
				(footprints allowed)
			)
			(placement
				(enabled no)
				(sheetname "")
			)
			(fill
				(thermal_gap 0.5)
				(thermal_bridge_width 0.5)
				(island_removal_mode 0)
			)
			(polygon
				(pts
					(xy 31.087568 -17.977612) (xy 31.087568 -17.469612) (xy 30.706568 -17.469612) (xy 30.706568 -17.977612)
				)
			)
		)
	)
	(footprint ""
		(layer "B.Cu")
		(at 321.1957 -32.93618 90)
		(property "Reference" "R4T4"
			(at 0 0 90)
			(layer "B.SilkS")
			(hide yes)
			(effects
				(font
					(size 1.27 1.27)
				)
				(justify mirror)
			)
		)
		(property "Value" ""
			(at 0 0 90)
			(layer "B.Fab")
			(effects
				(font
					(size 1.27 1.27)
				)
				(justify mirror)
			)
		)
		(duplicate_pad_numbers_are_jumpers no)
		(fp_poly
			(pts
				(xy 0.2794 -0.1016) (xy -0.2794 -0.1016) (xy -0.2794 0.9906) (xy 0.2794 0.9906)
			)
			(stroke
				(width 0)
				(type default)
			)
			(fill no)
			(layer "B.CrtYd")
		)
		(fp_line
			(start 0.2794 -0.1016)
			(end 0.2794 0.9906)
			(stroke
				(width 0.1)
				(type default)
			)
			(layer "B.Fab")
		)
		(fp_line
			(start -0.2794 -0.1016)
			(end 0.2794 -0.1016)
			(stroke
				(width 0.1)
				(type default)
			)
			(layer "B.Fab")
		)
		(fp_line
			(start 0.2794 0.9906)
			(end -0.2794 0.9906)
			(stroke
				(width 0.1)
				(type default)
			)
			(layer "B.Fab")
		)
		(fp_line
			(start -0.2794 0.9906)
			(end -0.2794 -0.1016)
			(stroke
				(width 0.1)
				(type default)
			)
			(layer "B.Fab")
		)
		(pad "1" smd rect
			(at 0 0 270)
			(size 0.508 0.508)
			(layers "B.Cu" "B.Mask" "B.Paste")
			(net "SMB_DDR_ABC_SDA_G_R")
		)
		(pad "2" smd rect
			(at 0 0.889 270)
			(size 0.508 0.508)
			(layers "B.Cu" "B.Mask" "B.Paste")
			(net "SMB_DDR_ABC_SDA_G")
		)
		(zone
			(layer "B.Cu")
			(hatch none 0.5)
			(connect_pads
				(clearance 0)
			)
			(min_thickness 0.25)
			(keepout
				(tracks allowed)
				(vias not_allowed)
				(pads allowed)
				(copperpour not_allowed)
				(footprints allowed)
			)
			(placement
				(enabled no)
				(sheetname "")
			)
			(fill
				(thermal_gap 0.5)
				(thermal_bridge_width 0.5)
				(island_removal_mode 0)
			)
			(polygon
				(pts
					(xy 321.4497 -33.19018) (xy 321.4497 -32.68218) (xy 321.8307 -32.68218) (xy 321.8307 -33.19018)
				)
			)
		)
		(zone
			(layer "B.Cu")
			(hatch none 0.5)
			(connect_pads
				(clearance 0)
			)
			(min_thickness 0.25)
			(keepout
				(tracks not_allowed)
				(vias allowed)
				(pads allowed)
				(copperpour not_allowed)
				(footprints allowed)
			)
			(placement
				(enabled no)
				(sheetname "")
			)
			(fill
				(thermal_gap 0.5)
				(thermal_bridge_width 0.5)
				(island_removal_mode 0)
			)
			(polygon
				(pts
					(xy 321.8307 -33.19018) (xy 321.8307 -32.68218) (xy 321.4497 -32.68218) (xy 321.4497 -33.19018)
				)
			)
		)
	)
	(footprint ""
		(layer "B.Cu")
		(at 409.3845 -26.035 -90)
		(property "Reference" "C25W69"
			(at -0.97536 0.76708 0)
			(unlocked yes)
			(layer "B.SilkS")
			(effects
				(font
					(size 0.4064 0.254)
					(thickness 0.1524)
				)
				(justify mirror)
			)
		)
		(property "Value" ""
			(at 0 0 90)
			(layer "B.Fab")
			(effects
				(font
					(size 1.27 1.27)
				)
				(justify mirror)
			)
		)
		(duplicate_pad_numbers_are_jumpers no)
		(fp_poly
			(pts
				(xy 0.4953 -0.2032) (xy -0.4953 -0.2032) (xy -0.4953 1.6002) (xy 0.4953 1.6002)
			)
			(stroke
				(width 0)
				(type default)
			)
			(fill no)
			(layer "B.CrtYd")
		)
		(fp_line
			(start -0.4953 1.6002)
			(end 0.4953 1.6002)
			(stroke
				(width 0.1)
				(type default)
			)
			(layer "B.Fab")
		)
		(fp_line
			(start 0.4953 1.6002)
			(end 0.4953 -0.2032)
			(stroke
				(width 0.1)
				(type default)
			)
			(layer "B.Fab")
		)
		(fp_line
			(start -0.4953 -0.2032)
			(end -0.4953 1.6002)
			(stroke
				(width 0.1)
				(type default)
			)
			(layer "B.Fab")
		)
		(fp_line
			(start 0.4953 -0.2032)
			(end -0.4953 -0.2032)
			(stroke
				(width 0.1)
				(type default)
			)
			(layer "B.Fab")
		)
		(pad "1" smd rect
			(at 0 0 90)
			(size 0.762 0.889)
			(layers "B.Cu" "B.Mask" "B.Paste")
			(net "VCC_VA_3V3")
		)
		(pad "2" smd rect
			(at 0 1.397 90)
			(size 0.762 0.889)
			(layers "B.Cu" "B.Mask" "B.Paste")
			(net "GND")
		)
		(zone
			(layer "B.Cu")
			(hatch none 0.5)
			(connect_pads
				(clearance 0)
			)
			(min_thickness 0.25)
			(keepout
				(tracks not_allowed)
				(vias allowed)
				(pads allowed)
				(copperpour not_allowed)
				(footprints allowed)
			)
			(placement
				(enabled no)
				(sheetname "")
			)
			(fill
				(thermal_gap 0.5)
				(thermal_bridge_width 0.5)
				(island_removal_mode 0)
			)
			(polygon
				(pts
					(xy 408.94 -25.654) (xy 408.94 -26.416) (xy 408.432 -26.416) (xy 408.432 -25.654)
				)
			)
		)
	)
	(footprint ""
		(layer "B.Cu")
		(at 496.529614 -47.605696 -90)
		(property "Reference" "R25W132"
			(at 0.8382 -0.67818 270)
			(unlocked yes)
			(layer "B.SilkS")
			(effects
				(font
					(size 0.4064 0.254)
					(thickness 0.1524)
				)
				(justify left mirror)
			)
		)
		(property "Value" ""
			(at 0 0 90)
			(layer "B.Fab")
			(effects
				(font
					(size 1.27 1.27)
				)
				(justify mirror)
			)
		)
		(duplicate_pad_numbers_are_jumpers no)
		(fp_poly
			(pts
				(xy 0.2794 -0.1016) (xy -0.2794 -0.1016) (xy -0.2794 0.9906) (xy 0.2794 0.9906)
			)
			(stroke
				(width 0)
				(type default)
			)
			(fill no)
			(layer "B.CrtYd")
		)
		(fp_line
			(start -0.2794 0.9906)
			(end -0.2794 -0.1016)
			(stroke
				(width 0.1)
				(type default)
			)
			(layer "B.Fab")
		)
		(fp_line
			(start 0.2794 0.9906)
			(end -0.2794 0.9906)
			(stroke
				(width 0.1)
				(type default)
			)
			(layer "B.Fab")
		)
		(fp_line
			(start -0.2794 -0.1016)
			(end 0.2794 -0.1016)
			(stroke
				(width 0.1)
				(type default)
			)
			(layer "B.Fab")
		)
		(fp_line
			(start 0.2794 -0.1016)
			(end 0.2794 0.9906)
			(stroke
				(width 0.1)
				(type default)
			)
			(layer "B.Fab")
		)
		(pad "1" smd rect
			(at 0 0 90)
			(size 0.508 0.508)
			(layers "B.Cu" "B.Mask" "B.Paste")
			(net "P5V_VGA_D")
		)
		(pad "2" smd rect
			(at 0 0.889 90)
			(size 0.508 0.508)
			(layers "B.Cu" "B.Mask" "B.Paste")
			(net "I2C_BMC_VGA_DDC_SCL_G")
		)
		(zone
			(layer "B.Cu")
			(hatch none 0.5)
			(connect_pads
				(clearance 0)
			)
			(min_thickness 0.25)
			(keepout
				(tracks not_allowed)
				(vias allowed)
				(pads allowed)
				(copperpour not_allowed)
				(footprints allowed)
			)
			(placement
				(enabled no)
				(sheetname "")
			)
			(fill
				(thermal_gap 0.5)
				(thermal_bridge_width 0.5)
				(island_removal_mode 0)
			)
			(polygon
				(pts
					(xy 495.894614 -47.351696) (xy 495.894614 -47.859696) (xy 496.275614 -47.859696) (xy 496.275614 -47.351696)
				)
			)
		)
		(zone
			(layer "B.Cu")
			(hatch none 0.5)
			(connect_pads
				(clearance 0)
			)
			(min_thickness 0.25)
			(keepout
				(tracks allowed)
				(vias not_allowed)
				(pads allowed)
				(copperpour not_allowed)
				(footprints allowed)
			)
			(placement
				(enabled no)
				(sheetname "")
			)
			(fill
				(thermal_gap 0.5)
				(thermal_bridge_width 0.5)
				(island_removal_mode 0)
			)
			(polygon
				(pts
					(xy 496.275614 -47.351696) (xy 496.275614 -47.859696) (xy 495.894614 -47.859696) (xy 495.894614 -47.351696)
				)
			)
		)
	)
)
